# BASEBOARD_FAB2 (Tioga Pass) — schematic netlist excerpt (pin names and nets, part order shuffled) for the footprints in the layout excerpt that follows; sources: Cadence DE-HDL packaged netlist, KiCad conversion of Wiwynn_Tioga_Pass_MB.brd

C7M6  CAPP  68UF 16V 20% TANT  pkg 3018  page 195 : A = P12V_STBY ; B = GND
R5N2  RES  1.8K 1% CHIP  pkg 0402  page 21 : A = P3V3_STBY ; B = FM_CPU0_PROC_ID1
C6P24  CAP  10UF 16V 10% X6S  pkg 0805  page 203 : A = VR_FET_SW_P12V_STBY_PVCCIN_CPU0 ; B = GND

(kicad_pcb
	(version 20260206)
	(generator "pcbnew")
	(generator_version "10.0")
	(general
		(thickness 1.6)
		(legacy_teardrops no)
	)
	(paper "A4")
	(title_block
		(title "Wiwynn_Tioga_Pass_MB.brd")
		(comment 1 "Tioga Pass / footprints 4501-4503 of 4770")
	)
	(layers
		(0 "F.Cu" signal "TOP")
		(4 "In1.Cu" signal "L2GND")
		(6 "In2.Cu" signal "L3")
		(8 "In3.Cu" signal "L4GND")
		(10 "In4.Cu" signal "L5")
		(12 "In5.Cu" signal "L6GND")
		(14 "In6.Cu" signal "L7VCC")
		(16 "In7.Cu" signal "L8VCC")
		(18 "In8.Cu" signal "L9GND")
		(20 "In9.Cu" signal "L10")
		(22 "In10.Cu" signal "L11GND")
		(24 "In11.Cu" signal "L12")
		(26 "In12.Cu" signal "L13GND")
		(2 "B.Cu" signal "BOTTOM")
		(9 "F.Adhes" user "F.Adhesive")
		(11 "B.Adhes" user "B.Adhesive")
		(13 "F.Paste" user "Package Geometry/Pastemask Top")
		(15 "B.Paste" user "Package Geometry/Pastemask Bottom")
		(5 "F.SilkS" user "Ref Des/Silkscreen Top")
		(7 "B.SilkS" user "Ref Des/Silkscreen Bottom")
		(1 "F.Mask" user "Board Geometry/Soldermask Top")
		(3 "B.Mask" user "Board Geometry/Soldermask Bottom")
		(17 "Dwgs.User" user "User.Drawings")
		(19 "Cmts.User" user "User.Comments")
		(21 "Eco1.User" user "User.Eco1")
		(23 "Eco2.User" user "User.Eco2")
		(25 "Edge.Cuts" user "Board Geometry/Outline")
		(27 "Margin" user)
		(31 "F.CrtYd" user "Package Geometry/Place Bound Top")
		(29 "B.CrtYd" user "Package Geometry/Place Bound Bottom")
		(35 "F.Fab" user "Ref Des/Assembly Top")
		(33 "B.Fab" user "Ref Des/Assembly Bottom")
	)
	(footprint ""
		(layer "B.Cu")
		(at 151.511 -122.809 -90)
		(property "Reference" "C7M6"
			(at -3.10007 3.24612 0)
			(unlocked yes)
			(layer "B.SilkS")
			(effects
				(font
					(size 0.7874 0.5842)
					(thickness 0.1524)
				)
				(justify mirror)
			)
		)
		(property "Value" ""
			(at 0 0 90)
			(layer "B.Fab")
			(effects
				(font
					(size 1.27 1.27)
				)
				(justify mirror)
			)
		)
		(duplicate_pad_numbers_are_jumpers no)
		(fp_line
			(start -2.286 7.366)
			(end -1.600708 7.366)
			(stroke
				(width 0.1524)
				(type default)
			)
			(layer "B.SilkS")
		)
		(fp_line
			(start -2.286 7.366)
			(end -2.286 1.63195)
			(stroke
				(width 0.1524)
				(type default)
			)
			(layer "B.SilkS")
		)
		(fp_line
			(start 2.286 7.366)
			(end 1.60147 7.366)
			(stroke
				(width 0.1524)
				(type default)
			)
			(layer "B.SilkS")
		)
		(fp_line
			(start 2.286 7.366)
			(end 2.286 1.632712)
			(stroke
				(width 0.1524)
				(type default)
			)
			(layer "B.SilkS")
		)
		(fp_line
			(start -2.504948 1.633728)
			(end -1.6002 1.633728)
			(stroke
				(width 0.1524)
				(type default)
			)
			(layer "B.SilkS")
		)
		(fp_line
			(start 2.563114 1.633728)
			(end 1.6002 1.633728)
			(stroke
				(width 0.1524)
				(type default)
			)
			(layer "B.SilkS")
		)
		(fp_line
			(start -2.504948 -1.616456)
			(end -2.504948 1.633728)
			(stroke
				(width 0.1524)
				(type default)
			)
			(layer "B.SilkS")
		)
		(fp_line
			(start -1.6002 -1.616456)
			(end -2.504948 -1.616456)
			(stroke
				(width 0.1524)
				(type default)
			)
			(layer "B.SilkS")
		)
		(fp_line
			(start 1.6002 -1.616456)
			(end 2.563114 -1.616456)
			(stroke
				(width 0.1524)
				(type default)
			)
			(layer "B.SilkS")
		)
		(fp_line
			(start 2.563114 -1.616456)
			(end 2.563114 1.633728)
			(stroke
				(width 0.1524)
				(type default)
			)
			(layer "B.SilkS")
		)
		(fp_rect
			(start 2.286 7.366)
			(end -2.286 -0.254)
			(stroke
				(width 0)
				(type default)
			)
			(fill no)
			(layer "B.CrtYd")
		)
		(fp_line
			(start -2.286 7.366)
			(end 2.286 7.366)
			(stroke
				(width 0.1)
				(type default)
			)
			(layer "B.Fab")
		)
		(fp_line
			(start 2.286 7.366)
			(end 2.286 -0.254)
			(stroke
				(width 0.1)
				(type default)
			)
			(layer "B.Fab")
		)
		(fp_line
			(start -2.286 -0.254)
			(end -2.286 7.366)
			(stroke
				(width 0.1)
				(type default)
			)
			(layer "B.Fab")
		)
		(fp_line
			(start 2.286 -0.254)
			(end -2.286 -0.254)
			(stroke
				(width 0.1)
				(type default)
			)
			(layer "B.Fab")
		)
		(pad "1" smd rect
			(at 0 0 90)
			(size 2.54 3.048)
			(layers "B.Cu" "B.Mask" "B.Paste")
			(net "P12V_STBY")
		)
		(pad "2" smd rect
			(at 0 7.112 90)
			(size 2.54 3.048)
			(layers "B.Cu" "B.Mask" "B.Paste")
			(net "GND")
		)
	)
	(footprint ""
		(layer "B.Cu")
		(at 227.584 -92.583 90)
		(property "Reference" "R5N2"
			(at 0 0 90)
			(layer "B.SilkS")
			(hide yes)
			(effects
				(font
					(size 1.27 1.27)
				)
				(justify mirror)
			)
		)
		(property "Value" ""
			(at 0 0 90)
			(layer "B.Fab")
			(effects
				(font
					(size 1.27 1.27)
				)
				(justify mirror)
			)
		)
		(duplicate_pad_numbers_are_jumpers no)
		(fp_poly
			(pts
				(xy 0.2794 -0.1016) (xy -0.2794 -0.1016) (xy -0.2794 0.9906) (xy 0.2794 0.9906)
			)
			(stroke
				(width 0)
				(type default)
			)
			(fill no)
			(layer "B.CrtYd")
		)
		(fp_line
			(start 0.2794 -0.1016)
			(end 0.2794 0.9906)
			(stroke
				(width 0.1)
				(type default)
			)
			(layer "B.Fab")
		)
		(fp_line
			(start -0.2794 -0.1016)
			(end 0.2794 -0.1016)
			(stroke
				(width 0.1)
				(type default)
			)
			(layer "B.Fab")
		)
		(fp_line
			(start 0.2794 0.9906)
			(end -0.2794 0.9906)
			(stroke
				(width 0.1)
				(type default)
			)
			(layer "B.Fab")
		)
		(fp_line
			(start -0.2794 0.9906)
			(end -0.2794 -0.1016)
			(stroke
				(width 0.1)
				(type default)
			)
			(layer "B.Fab")
		)
		(pad "1" smd rect
			(at 0 0 270)
			(size 0.508 0.508)
			(layers "B.Cu" "B.Mask" "B.Paste")
			(net "P3V3_STBY")
		)
		(pad "2" smd rect
			(at 0 0.889 270)
			(size 0.508 0.508)
			(layers "B.Cu" "B.Mask" "B.Paste")
			(net "FM_CPU0_PROC_ID1")
		)
		(zone
			(layer "B.Cu")
			(hatch none 0.5)
			(connect_pads
				(clearance 0)
			)
			(min_thickness 0.25)
			(keepout
				(tracks allowed)
				(vias not_allowed)
				(pads allowed)
				(copperpour not_allowed)
				(footprints allowed)
			)
			(placement
				(enabled no)
				(sheetname "")
			)
			(fill
				(thermal_gap 0.5)
				(thermal_bridge_width 0.5)
				(island_removal_mode 0)
			)
			(polygon
				(pts
					(xy 227.838 -92.837) (xy 227.838 -92.329) (xy 228.219 -92.329) (xy 228.219 -92.837)
				)
			)
		)
		(zone
			(layer "B.Cu")
			(hatch none 0.5)
			(connect_pads
				(clearance 0)
			)
			(min_thickness 0.25)
			(keepout
				(tracks not_allowed)
				(vias allowed)
				(pads allowed)
				(copperpour not_allowed)
				(footprints allowed)
			)
			(placement
				(enabled no)
				(sheetname "")
			)
			(fill
				(thermal_gap 0.5)
				(thermal_bridge_width 0.5)
				(island_removal_mode 0)
			)
			(polygon
				(pts
					(xy 228.219 -92.837) (xy 228.219 -92.329) (xy 227.838 -92.329) (xy 227.838 -92.837)
				)
			)
		)
	)
	(footprint ""
		(layer "B.Cu")
		(at 197.848728 -66.327782 90)
		(property "Reference" "C6P24"
			(at 0 0 90)
			(layer "B.SilkS")
			(hide yes)
			(effects
				(font
					(size 1.27 1.27)
				)
				(justify mirror)
			)
		)
		(property "Value" ""
			(at 0 0 90)
			(layer "B.Fab")
			(effects
				(font
					(size 1.27 1.27)
				)
				(justify mirror)
			)
		)
		(duplicate_pad_numbers_are_jumpers no)
		(fp_rect
			(start 0.7239 1.9939)
			(end -0.7239 -0.2159)
			(stroke
				(width 0)
				(type default)
			)
			(fill no)
			(layer "B.CrtYd")
		)
		(fp_line
			(start 0.7239 -0.2159)
			(end 0.7239 1.9939)
			(stroke
				(width 0.1)
				(type default)
			)
			(layer "B.Fab")
		)
		(fp_line
			(start -0.7239 -0.2159)
			(end 0.7239 -0.2159)
			(stroke
				(width 0.1)
				(type default)
			)
			(layer "B.Fab")
		)
		(fp_line
			(start 0.7239 1.9939)
			(end -0.7239 1.9939)
			(stroke
				(width 0.1)
				(type default)
			)
			(layer "B.Fab")
		)
		(fp_line
			(start -0.7239 1.9939)
			(end -0.7239 -0.2159)
			(stroke
				(width 0.1)
				(type default)
			)
			(layer "B.Fab")
		)
		(pad "1" smd rect
			(at 0 0 270)
			(size 1.27 1.016)
			(layers "B.Cu" "B.Mask" "B.Paste")
			(net "VR_FET_SW_P12V_STBY_PVCCIN_CPU0")
		)
		(pad "2" smd rect
			(at 0 1.778 270)
			(size 1.27 1.016)
			(layers "B.Cu" "B.Mask" "B.Paste")
			(net "GND")
		)
		(zone
			(layer "B.Cu")
			(hatch none 0.5)
			(connect_pads
				(clearance 0)
			)
			(min_thickness 0.25)
			(keepout
				(tracks not_allowed)
				(vias allowed)
				(pads allowed)
				(copperpour not_allowed)
				(footprints allowed)
			)
			(placement
				(enabled no)
				(sheetname "")
			)
			(fill
				(thermal_gap 0.5)
				(thermal_bridge_width 0.5)
				(island_removal_mode 0)
			)
			(polygon
				(pts
					(xy 199.118728 -66.962782) (xy 198.356728 -66.962782) (xy 198.356728 -65.692782) (xy 199.118728 -65.692782)
				)
			)
		)
	)
)
